# SCM (Grand Teton) — schematic netlist excerpt (pin names and nets, part order shuffled) for the footprints in the layout excerpt that follows; sources: Cadence DE-HDL packaged netlist, KiCad conversion of 12092022_DA0F0TMDCD0_F0T_Management_Board_D_brd_V3_OCP.brd

R805  Q_RES  4.7K 1% CHIP  pkg 0402LF  page 13 : A = P3V3_AUX ; B = BMC_HEARTBEAT_N
R395  Q_RES  0 5% CHIP  pkg 0402LF  page 13 : A = PWRGD_P1V0_AUX_DELAY_R ; B = PWRGD_P1V0_AUX_DELAY

(kicad_pcb
	(version 20260206)
	(generator "pcbnew")
	(generator_version "10.0")
	(general
		(thickness 1.6)
		(legacy_teardrops no)
	)
	(paper "A4")
	(title_block
		(title "12092022_DA0F0TMDCD0_F0T_Management_Board_D_brd_V3_OCP.brd")
		(comment 1 "Grand Teton / footprints 112-113 of 1440")
	)
	(layers
		(0 "F.Cu" signal "TOP")
		(4 "In1.Cu" signal "GND")
		(6 "In2.Cu" signal "IN1")
		(8 "In3.Cu" signal "GND1")
		(10 "In4.Cu" signal "IN2")
		(12 "In5.Cu" signal "VCC")
		(14 "In6.Cu" signal "VCC1")
		(16 "In7.Cu" signal "IN3")
		(18 "In8.Cu" signal "GND2")
		(20 "In9.Cu" signal "IN4")
		(22 "In10.Cu" signal "GND3")
		(2 "B.Cu" signal "BOTTOM")
		(9 "F.Adhes" user "F.Adhesive")
		(11 "B.Adhes" user "B.Adhesive")
		(13 "F.Paste" user "Package Geometry/Pastemask Top")
		(15 "B.Paste" user "Package Geometry/Pastemask Bottom")
		(5 "F.SilkS" user "Ref Des/Silkscreen Top")
		(7 "B.SilkS" user "Ref Des/Silkscreen Bottom")
		(1 "F.Mask" user "Board Geometry/Soldermask Top")
		(3 "B.Mask" user "Board Geometry/Soldermask Bottom")
		(17 "Dwgs.User" user "User.Drawings")
		(19 "Cmts.User" user "User.Comments")
		(21 "Eco1.User" user "User.Eco1")
		(23 "Eco2.User" user "User.Eco2")
		(25 "Edge.Cuts" user "Board Geometry/Outline")
		(27 "Margin" user)
		(31 "F.CrtYd" user "Package Geometry/Place Bound Top")
		(29 "B.CrtYd" user "Package Geometry/Place Bound Bottom")
		(35 "F.Fab" user "Ref Des/Assembly Top")
		(33 "B.Fab" user "Ref Des/Assembly Bottom")
	)
	(footprint ""
		(layer "F.Cu")
		(at 45.212 -26.8732 90)
		(property "Reference" "R395"
			(at 0 0 90)
			(layer "F.SilkS")
			(hide yes)
			(effects
				(font
					(size 1.27 1.27)
				)
			)
		)
		(property "Value" ""
			(at 0 0 90)
			(layer "F.Fab")
			(effects
				(font
					(size 1.27 1.27)
				)
			)
		)
		(duplicate_pad_numbers_are_jumpers no)
		(fp_line
			(start 0.7874 -0.4064)
			(end 0.7874 0.4064)
			(stroke
				(width 0.1524)
				(type default)
			)
			(layer "F.SilkS")
		)
		(fp_line
			(start -0.7874 -0.4064)
			(end 0.7874 -0.4064)
			(stroke
				(width 0.1524)
				(type default)
			)
			(layer "F.SilkS")
		)
		(fp_line
			(start 0.7874 0.4064)
			(end -0.7874 0.4064)
			(stroke
				(width 0.1524)
				(type default)
			)
			(layer "F.SilkS")
		)
		(fp_line
			(start -0.7874 0.4064)
			(end -0.7874 -0.4064)
			(stroke
				(width 0.1524)
				(type default)
			)
			(layer "F.SilkS")
		)
		(fp_line
			(start -0.12065 -0.305054)
			(end -0.12065 -0.2794)
			(stroke
				(width 0.1)
				(type default)
			)
			(layer "F.Fab")
		)
		(fp_line
			(start -0.67945 -0.305054)
			(end -0.12065 -0.305054)
			(stroke
				(width 0.1)
				(type default)
			)
			(layer "F.Fab")
		)
		(fp_line
			(start 0.67945 -0.3048)
			(end 0.67945 0.3048)
			(stroke
				(width 0.1)
				(type default)
			)
			(layer "F.Fab")
		)
		(fp_line
			(start 0.12065 -0.3048)
			(end 0.67945 -0.3048)
			(stroke
				(width 0.1)
				(type default)
			)
			(layer "F.Fab")
		)
		(fp_line
			(start 0.12065 -0.2794)
			(end 0.12065 -0.3048)
			(stroke
				(width 0.1)
				(type default)
			)
			(layer "F.Fab")
		)
		(fp_line
			(start -0.12065 -0.2794)
			(end 0.12065 -0.2794)
			(stroke
				(width 0.1)
				(type default)
			)
			(layer "F.Fab")
		)
		(fp_line
			(start 0.120396 0.2794)
			(end -0.12065 0.2794)
			(stroke
				(width 0.1)
				(type default)
			)
			(layer "F.Fab")
		)
		(fp_line
			(start -0.12065 0.2794)
			(end -0.12065 0.3048)
			(stroke
				(width 0.1)
				(type default)
			)
			(layer "F.Fab")
		)
		(fp_line
			(start 0.67945 0.3048)
			(end 0.120396 0.3048)
			(stroke
				(width 0.1)
				(type default)
			)
			(layer "F.Fab")
		)
		(fp_line
			(start 0.120396 0.3048)
			(end 0.120396 0.2794)
			(stroke
				(width 0.1)
				(type default)
			)
			(layer "F.Fab")
		)
		(fp_line
			(start -0.12065 0.3048)
			(end -0.67945 0.3048)
			(stroke
				(width 0.1)
				(type default)
			)
			(layer "F.Fab")
		)
		(fp_line
			(start -0.67945 0.3048)
			(end -0.67945 -0.305054)
			(stroke
				(width 0.1)
				(type default)
			)
			(layer "F.Fab")
		)
		(pad "1" smd circle
			(at -0.40005 0 90)
			(size 0 0)
			(layers "F.Cu" "F.Mask" "F.Paste")
			(net "PWRGD_P1V0_AUX_DELAY_R")
		)
		(pad "2" smd circle
			(at 0.40005 0 90)
			(size 0 0)
			(layers "F.Cu" "F.Mask" "F.Paste")
			(net "PWRGD_P1V0_AUX_DELAY")
		)
	)
	(footprint ""
		(layer "F.Cu")
		(at 45.5676 -69.2912)
		(property "Reference" "R805"
			(at 0 0 0)
			(layer "F.SilkS")
			(hide yes)
			(effects
				(font
					(size 1.27 1.27)
				)
			)
		)
		(property "Value" ""
			(at 0 0 0)
			(layer "F.Fab")
			(effects
				(font
					(size 1.27 1.27)
				)
			)
		)
		(duplicate_pad_numbers_are_jumpers no)
		(fp_line
			(start -0.7874 -0.4064)
			(end 0.7874 -0.4064)
			(stroke
				(width 0.1524)
				(type default)
			)
			(layer "F.SilkS")
		)
		(fp_line
			(start -0.7874 0.4064)
			(end -0.7874 -0.4064)
			(stroke
				(width 0.1524)
				(type default)
			)
			(layer "F.SilkS")
		)
		(fp_line
			(start 0.7874 -0.4064)
			(end 0.7874 0.4064)
			(stroke
				(width 0.1524)
				(type default)
			)
			(layer "F.SilkS")
		)
		(fp_line
			(start 0.7874 0.4064)
			(end -0.7874 0.4064)
			(stroke
				(width 0.1524)
				(type default)
			)
			(layer "F.SilkS")
		)
		(fp_line
			(start -0.67945 -0.305054)
			(end -0.12065 -0.305054)
			(stroke
				(width 0.1)
				(type default)
			)
			(layer "F.Fab")
		)
		(fp_line
			(start -0.67945 0.3048)
			(end -0.67945 -0.305054)
			(stroke
				(width 0.1)
				(type default)
			)
			(layer "F.Fab")
		)
		(fp_line
			(start -0.12065 -0.305054)
			(end -0.12065 -0.2794)
			(stroke
				(width 0.1)
				(type default)
			)
			(layer "F.Fab")
		)
		(fp_line
			(start -0.12065 -0.2794)
			(end 0.12065 -0.2794)
			(stroke
				(width 0.1)
				(type default)
			)
			(layer "F.Fab")
		)
		(fp_line
			(start -0.12065 0.2794)
			(end -0.12065 0.3048)
			(stroke
				(width 0.1)
				(type default)
			)
			(layer "F.Fab")
		)
		(fp_line
			(start -0.12065 0.3048)
			(end -0.67945 0.3048)
			(stroke
				(width 0.1)
				(type default)
			)
			(layer "F.Fab")
		)
		(fp_line
			(start 0.120396 0.2794)
			(end -0.12065 0.2794)
			(stroke
				(width 0.1)
				(type default)
			)
			(layer "F.Fab")
		)
		(fp_line
			(start 0.120396 0.3048)
			(end 0.120396 0.2794)
			(stroke
				(width 0.1)
				(type default)
			)
			(layer "F.Fab")
		)
		(fp_line
			(start 0.12065 -0.3048)
			(end 0.67945 -0.3048)
			(stroke
				(width 0.1)
				(type default)
			)
			(layer "F.Fab")
		)
		(fp_line
			(start 0.12065 -0.2794)
			(end 0.12065 -0.3048)
			(stroke
				(width 0.1)
				(type default)
			)
			(layer "F.Fab")
		)
		(fp_line
			(start 0.67945 -0.3048)
			(end 0.67945 0.3048)
			(stroke
				(width 0.1)
				(type default)
			)
			(layer "F.Fab")
		)
		(fp_line
			(start 0.67945 0.3048)
			(end 0.120396 0.3048)
			(stroke
				(width 0.1)
				(type default)
			)
			(layer "F.Fab")
		)
		(pad "1" smd circle
			(at -0.40005 0)
			(size 0 0)
			(layers "F.Cu" "F.Mask" "F.Paste")
			(net "P3V3_AUX")
		)
		(pad "2" smd circle
			(at 0.40005 0)
			(size 0 0)
			(layers "F.Cu" "F.Mask" "F.Paste")
			(net "BMC_HEARTBEAT_N")
		)
	)
)
